# BASEBOARD_FAB2 (Tioga Pass) — schematic parts with pin connectivity, parts 2365–2366 of 4751; source: Cadence DE-HDL packaged netlist (pstxprt.dat, pstxnet.dat, pstchip.dat)

J4B1  SCONN288_H44441004  SCONN  pkg PIP  page 49
  1  \12v\(1)  = P12V_NVDIMM_DEF
  2  VSS(93)  GROUND  = GND
  3  DQ(4)  BI  = M_D_DQ<5>
  4  VSS(92)  GROUND  = GND
  5  DQ(0)  BI  = M_D_DQ<1>
  6  VSS(91)  GROUND  = GND
  7  DQS9P  BI  = M_D_DQS_DP<9>
  8  DQS9N  BI  = M_D_DQS_DN<9>
  9  VSS(90)  GROUND  = GND
  10  DQ(6)  BI  = M_D_DQ<7>
  11  VSS(89)  GROUND  = GND
  12  DQ(2)  BI  = M_D_DQ<3>
  13  VSS(88)  GROUND  = GND
  14  DQ(12)  BI  = M_D_DQ<13>
  15  VSS(87)  GROUND  = GND
  16  DQ(8)  BI  = M_D_DQ<9>
  17  VSS(86)  GROUND  = GND
  18  DQS10P  BI  = M_D_DQS_DP<10>
  19  DQS10N  BI  = M_D_DQS_DN<10>
  20  VSS(85)  GROUND  = GND
  21  DQ(14)  BI  = M_D_DQ<15>
  22  VSS(84)  GROUND  = GND
  23  DQ(10)  BI  = M_D_DQ<11>
  24  VSS(83)  GROUND  = GND
  25  DQ(20)  BI  = M_D_DQ<21>
  26  VSS(82)  GROUND  = GND
  27  DQ(16)  BI  = M_D_DQ<17>
  28  VSS(81)  GROUND  = GND
  29  DQS11P  BI  = M_D_DQS_DP<11>
  30  DQS11N  BI  = M_D_DQS_DN<11>
  31  VSS(80)  GROUND  = GND
  32  DQ(22)  BI  = M_D_DQ<23>
  33  VSS(79)  GROUND  = GND
  34  DQ(18)  BI  = M_D_DQ<19>
  35  VSS(78)  GROUND  = GND
  36  DQ(28)  BI  = M_D_DQ<29>
  37  VSS(77)  GROUND  = GND
  38  DQ(24)  BI  = M_D_DQ<25>
  39  VSS(76)  GROUND  = GND
  40  DQS12P  BI  = M_D_DQS_DP<12>
  41  DQS12N  BI  = M_D_DQS_DN<12>
  42  VSS(75)  GROUND  = GND
  43  DQ(30)  BI  = M_D_DQ<31>
  44  VSS(74)  GROUND  = GND
  45  DQ(26)  BI  = M_D_DQ<27>
  46  VSS(73)  GROUND  = GND
  47  CB(4)  BI  = M_D_ECC<5>
  48  VSS(72)  GROUND  = GND
  49  CB(0)  BI  = M_D_ECC<1>
  50  VSS(71)  GROUND  = GND
  51  DQS17P  BI  = M_D_DQS_DP<17>
  52  DQS17N  BI  = M_D_DQS_DN<17>
  53  VSS(70)  GROUND  = GND
  54  CB(6)  BI  = M_D_ECC<7>
  55  VSS(69)  GROUND  = GND
  56  CB(2)  BI  = M_D_ECC<3>
  57  VSS(68)  GROUND  = GND
  58  RESET_N  BI  = M_DEF_RST_N
  59  VDD(25)  POWER  = PVDDQ_DEF
  60  CKE(0)  BI  = M_D_CKE<0>
  61  VDD(24)  POWER  = PVDDQ_DEF
  62  ACT_N  BI  = M_D_ACT_N
  63  BG(0)  BI  = M_D_BG<0>
  64  VDD(23)  POWER  = PVDDQ_DEF
  65  A12  BI  = M_D_MA<12>
  66  A9  BI  = M_D_MA<9>
  67  VDD(22)  POWER  = PVDDQ_DEF
  68  A8  BI  = M_D_MA<8>
  69  A6  BI  = M_D_MA<6>
  70  VDD(21)  POWER  = PVDDQ_DEF
  71  A3  BI  = M_D_MA<3>
  72  A1  BI  = M_D_MA<1>
  73  VDD(20)  POWER  = PVDDQ_DEF
  74  CK0P  BI  = M_D_CLK_DP<0>
  75  CK0N  BI  = M_D_CLK_DN<0>
  76  VDD(19)  POWER  = PVDDQ_DEF
  77  VTT(1)  POWER  = PVTT_DEF
  78  EVENT_N  BI  = FM_DIMM_EVENT_COD_N
  79  A0  BI  = M_D_MA<0>
  80  VDD(18)  POWER  = PVDDQ_DEF
  81  BA(0)  BI  = M_D_BA<0>
  82  A16_RAS_N  BI  = M_D_MA<16>
  83  VDD(17)  POWER  = PVDDQ_DEF
  84  S0_N  BI  = M_D_CS_N<0>
  85  VDD(16)  POWER  = PVDDQ_DEF
  86  A15_CAS_N  BI  = M_D_MA<15>
  87  ODT(0)  BI  = M_D_ODT<0>
  88  VDD(15)  POWER  = PVDDQ_DEF
  89  S1_N  BI  = M_D_CS_N<1>
  90  VDD(14)  POWER  = PVDDQ_DEF
  91  ODT(1)  BI  = M_D_ODT<1>
  92  VDD(13)  POWER  = PVDDQ_DEF
  93  S2_N_C(0)  BI  = M_D_CS_N<2>
  94  VSS(67)  GROUND  = GND
  95  DQ(36)  BI  = M_D_DQ<37>
  96  VSS(66)  GROUND  = GND
  97  DQ(32)  BI  = M_D_DQ<33>
  98  VSS(65)  GROUND  = GND
  99  DQS13P  BI  = M_D_DQS_DP<13>
  100  DQS13N  BI  = M_D_DQS_DN<13>
  101  VSS(64)  GROUND  = GND
  102  DQ(38)  BI  = M_D_DQ<39>
  103  VSS(63)  GROUND  = GND
  104  DQ(34)  BI  = M_D_DQ<35>
  105  VSS(62)  GROUND  = GND
  106  DQ(44)  BI  = M_D_DQ<45>
  107  VSS(61)  GROUND  = GND
  108  DQ(40)  BI  = M_D_DQ<41>
  109  VSS(60)  GROUND  = GND
  110  DQS14P  BI  = M_D_DQS_DP<14>
  111  DQS14N  BI  = M_D_DQS_DN<14>
  112  VSS(59)  GROUND  = GND
  113  DQ(46)  BI  = M_D_DQ<47>
  114  VSS(58)  GROUND  = GND
  115  DQ(42)  BI  = M_D_DQ<43>
  116  VSS(57)  GROUND  = GND
  117  DQ(52)  BI  = M_D_DQ<53>
  118  VSS(56)  GROUND  = GND
  119  DQ(48)  BI  = M_D_DQ<49>
  120  VSS(55)  GROUND  = GND
  121  DQS15P  BI  = M_D_DQS_DP<15>
  122  DQS15N  BI  = M_D_DQS_DN<15>
  123  VSS(54)  GROUND  = GND
  124  DQ(54)  BI  = M_D_DQ<55>
  125  VSS(53)  GROUND  = GND
  126  DQ(50)  BI  = M_D_DQ<51>
  127  VSS(52)  GROUND  = GND
  128  DQ(60)  BI  = M_D_DQ<61>
  129  VSS(51)  GROUND  = GND
  130  DQ(56)  BI  = M_D_DQ<57>
  131  VSS(50)  GROUND  = GND
  132  DQS16P  BI  = M_D_DQS_DP<16>
  133  DQS16N  BI  = M_D_DQS_DN<16>
  134  VSS(49)  GROUND  = GND
  135  DQ(62)  BI  = M_D_DQ<63>
  136  VSS(48)  GROUND  = GND
  137  DQ(58)  BI  = M_D_DQ<59>
  138  VSS(47)  GROUND  = GND
  139  SA(0)  BI  = GND
  140  SA(1)  BI  = GND
  141  SCL  BI  = SMB_DDR_DEF_VPP_SCL
  142  VPP(4)  POWER  = PVPP_DEF
  143  VPP(3)  POWER  = PVPP_DEF
  144  RFU(2)  BI  = TP_CH_D_DIMM_D0_RFU_2
  145  \12v\(0)  = P12V_NVDIMM_DEF
  146  VREFCA  BI  = M_D_VREF
  147  VSS(46)  GROUND  = GND
  148  DQ(5)  BI  = M_D_DQ<4>
  149  VSS(45)  GROUND  = GND
  150  DQ(1)  BI  = M_D_DQ<0>
  151  VSS(44)  GROUND  = GND
  152  DQS0N  BI  = M_D_DQS_DN<0>
  153  DQS0P  BI  = M_D_DQS_DP<0>
  154  VSS(43)  GROUND  = GND
  155  DQ(7)  BI  = M_D_DQ<6>
  156  VSS(42)  GROUND  = GND
  157  DQ(3)  BI  = M_D_DQ<2>
  158  VSS(41)  GROUND  = GND
  159  DQ(13)  BI  = M_D_DQ<12>
  160  VSS(40)  GROUND  = GND
  161  DQ(9)  BI  = M_D_DQ<8>
  162  VSS(39)  GROUND  = GND
  163  DQS1N  BI  = M_D_DQS_DN<1>
  164  DQS1P  BI  = M_D_DQS_DP<1>
  165  VSS(38)  GROUND  = GND
  166  DQ(15)  BI  = M_D_DQ<14>
  167  VSS(37)  GROUND  = GND
  168  DQ(11)  BI  = M_D_DQ<10>
  169  VSS(36)  GROUND  = GND
  170  DQ(21)  BI  = M_D_DQ<20>
  171  VSS(35)  GROUND  = GND
  172  DQ(17)  BI  = M_D_DQ<16>
  173  VSS(34)  GROUND  = GND
  174  DQS2N  BI  = M_D_DQS_DN<2>
  175  DQS2P  BI  = M_D_DQS_DP<2>
  176  VSS(33)  GROUND  = GND
  177  DQ(23)  BI  = M_D_DQ<22>
  178  VSS(32)  GROUND  = GND
  179  DQ(19)  BI  = M_D_DQ<18>
  180  VSS(31)  GROUND  = GND
  181  DQ(29)  BI  = M_D_DQ<28>
  182  VSS(30)  GROUND  = GND
  183  DQ(25)  BI  = M_D_DQ<24>
  184  VSS(29)  GROUND  = GND
  185  DQS3N  BI  = M_D_DQS_DN<3>
  186  DQS3P  BI  = M_D_DQS_DP<3>
  187  VSS(28)  GROUND  = GND
  188  DQ(31)  BI  = M_D_DQ<30>
  189  VSS(27)  GROUND  = GND
  190  DQ(27)  BI  = M_D_DQ<26>
  191  VSS(26)  GROUND  = GND
  192  CB(5)  BI  = M_D_ECC<4>
  193  VSS(25)  GROUND  = GND
  194  CB(1)  BI  = M_D_ECC<0>
  195  VSS(24)  GROUND  = GND
  196  DQS8N  BI  = M_D_DQS_DN<8>
  197  DQS8P  BI  = M_D_DQS_DP<8>
  198  VSS(23)  GROUND  = GND
  199  CB(7)  BI  = M_D_ECC<6>
  200  VSS(22)  GROUND  = GND
  201  CB(3)  BI  = M_D_ECC<2>
  202  VSS(21)  GROUND  = GND
  203  CKE(1)  BI  = M_D_CKE<1>
  204  VDD(12)  POWER  = PVDDQ_DEF
  205  RFU(0)  BI  = TP_CH_D_DIMM_D0_RFU_0
  206  VDD(11)  POWER  = PVDDQ_DEF
  207  BG(1)  BI  = M_D_BG<1>
  208  ALERT_N  BI  = M_D_ALERT_N
  209  VDD(10)  POWER  = PVDDQ_DEF
  210  A11  BI  = M_D_MA<11>
  211  A7  BI  = M_D_MA<7>
  212  VDD(9)  POWER  = PVDDQ_DEF
  213  A5  BI  = M_D_MA<5>
  214  A4  BI  = M_D_MA<4>
  215  VDD(8)  POWER  = PVDDQ_DEF
  216  A2  BI  = M_D_MA<2>
  217  VDD(7)  POWER  = PVDDQ_DEF
  218  CK1P  BI  = M_D_CLK_DP<1>
  219  CK1N  BI  = M_D_CLK_DN<1>
  220  VDD(6)  POWER  = PVDDQ_DEF
  221  VTT(0)  POWER  = PVTT_DEF
  222  PAR  BI  = M_D_PAR
  223  VDD(5)  POWER  = PVDDQ_DEF
  224  BA(1)  BI  = M_D_BA<1>
  225  A10  BI  = M_D_MA<10>
  226  VDD(4)  POWER  = PVDDQ_DEF
  227  RFU(1)  BI  = TP_CH_D_DIMM_D0_RFU_1
  228  A14_WE_N  BI  = M_D_MA<14>
  229  VDD(3)  POWER  = PVDDQ_DEF
  230  SAVE_N_NC  BI  = FM_ADR_COMPLETE_DEF_N
  231  VDD(2)  POWER  = PVDDQ_DEF
  232  A13  BI  = M_D_MA<13>
  233  VDD(1)  POWER  = PVDDQ_DEF
  234  A17  BI  = M_D_MA<17>
  235  C(2)  BI  = M_D_C<2>
  236  VDD(0)  POWER  = PVDDQ_DEF
  237  S3_N_C(1)  BI  = M_D_CS_N<3>
  238  SA(2)  BI  = GND
  239  VSS(20)  GROUND  = GND
  240  DQ(37)  BI  = M_D_DQ<36>
  241  VSS(19)  GROUND  = GND
  242  DQ(33)  BI  = M_D_DQ<32>
  243  VSS(18)  GROUND  = GND
  244  DQS4N  BI  = M_D_DQS_DN<4>
  245  DQS4P  BI  = M_D_DQS_DP<4>
  246  VSS(17)  GROUND  = GND
  247  DQ(39)  BI  = M_D_DQ<38>
  248  VSS(16)  GROUND  = GND
  249  DQ(35)  BI  = M_D_DQ<34>
  250  VSS(15)  GROUND  = GND
  251  DQ(45)  BI  = M_D_DQ<44>
  252  VSS(14)  GROUND  = GND
  253  DQ(41)  BI  = M_D_DQ<40>
  254  VSS(13)  GROUND  = GND
  255  DQS5N  BI  = M_D_DQS_DN<5>
  256  DQS5P  BI  = M_D_DQS_DP<5>
  257  VSS(12)  GROUND  = GND
  258  DQ(47)  BI  = M_D_DQ<46>
  259  VSS(11)  GROUND  = GND
  260  DQ(43)  BI  = M_D_DQ<42>
  261  VSS(10)  GROUND  = GND
  262  DQ(53)  BI  = M_D_DQ<52>
  263  VSS(9)  GROUND  = GND
  264  DQ(49)  BI  = M_D_DQ<48>
  265  VSS(8)  GROUND  = GND
  266  DQS6N  BI  = M_D_DQS_DN<6>
  267  DQS6P  BI  = M_D_DQS_DP<6>
  268  VSS(7)  GROUND  = GND
  269  DQ(55)  BI  = M_D_DQ<54>
  270  VSS(6)  GROUND  = GND
  271  DQ(51)  BI  = M_D_DQ<50>
  272  VSS(5)  GROUND  = GND
  273  DQ(61)  BI  = M_D_DQ<60>
  274  VSS(4)  GROUND  = GND
  275  DQ(57)  BI  = M_D_DQ<56>
  276  VSS(3)  GROUND  = GND
  277  DQS7N  BI  = M_D_DQS_DN<7>
  278  DQS7P  BI  = M_D_DQS_DP<7>
  279  VSS(2)  GROUND  = GND
  280  DQ(63)  BI  = M_D_DQ<62>
  281  VSS(1)  GROUND  = GND
  282  DQ(59)  BI  = M_D_DQ<58>
  283  VSS(0)  GROUND  = GND
  284  VDDSPD  BI  = PVPP_DEF
  285  SDA  BI  = SMB_DDR_DEF_VPP_SDA
  286  VPP(1)  POWER  = PVPP_DEF
  287  VPP(0)  POWER  = PVPP_DEF
  288  VPP(2)  POWER  = PVPP_DEF

J4B2  SCONN120_H61426002  CONN  pkg SM  page 193
  A1  IOA1  BI  = P12V_STBY
  A2  IOA2  BI  = P12V_STBY
  A3  IOA3  BI  = P12V_STBY
  A4  IOA4  BI  = P12V_STBY
  A5  IOA5  BI  = P12V_STBY
  A6  IOA6  BI  = P12V_STBY
  A7  IOA7  BI  = P12V_STBY
  A8  IOA8  BI  = P12V_STBY
  A9  IOA9  BI  = GND
  A10  IOA10  BI  = GND
  A11  IOA11  BI  = P3V3_STBY
  A12  IOA12  BI  = GND
  A13  IOA13  BI  = P5V_STBY
  A14  IOA14  BI  = GND
  A15  IOA15  BI  = FM_P1V8MCP_CPU1_EN
  A16  IOA16  BI  = FM_PVCCIOMCP_CPU1_EN
  A17  IOA17  BI  = GND
  A18  IOA18  BI  = SMB_VR_STBY_LVC3_SCL
  A19  IOA19  BI  = SVID_ALERT0_CPU1_R_N
  A20  IOA20  BI  = SVID_CLK0_CPU1_R
  B1  IOB1  BI  = P12V_STBY
  B2  IOB2  BI  = P12V_STBY
  B3  IOB3  BI  = P12V_STBY
  B4  IOB4  BI  = P12V_STBY
  B5  IOB5  BI  = P12V_STBY
  B6  IOB6  BI  = P12V_STBY
  B7  IOB7  BI  = P12V_STBY
  B8  IOB8  BI  = P12V_STBY
  B9  IOB9  BI  = GND
  B10  IOB10  BI  = GND
  B11  IOB11  BI  = P3V3_STBY
  B12  IOB12  BI  = GND
  B13  IOB13  BI  = P5V_STBY
  B14  IOB14  BI  = GND
  B15  IOB15  BI  = PWRGD_P1V8MCP_CPU1
  B16  IOB16  BI  = PWRGD_PVCCIOMCP_CPU1
  B17  IOB17  BI  = GND
  B18  IOB18  BI  = SMB_VR_STBY_LVC3_SDA
  B19  IOB19  BI  = SVID_ALERT1_CPU1_R_N
  B20  IOB20  BI  = SVID_DIO0_CPU1_R
  C1  IOC1  BI  = GND
  C2  IOC2  BI  = GND
  C3  IOC3  BI  = GND
  C4  IOC4  BI  = GND
  C5  IOC5  BI  = GND
  C6  IOC6  BI  = GND
  C7  IOC7  BI  = GND
  C8  IOC8  BI  = GND
  C9  IOC9  BI  = GND
  C10  IOC10  BI  = GND
  C11  IOC11  BI  = P3V3_STBY
  C12  IOC12  BI  = GND
  C13  IOC13  BI  = P5V_STBY
  C14  IOC14  BI  = GND
  C15  IOC15  BI  = GND
  C16  IOC16  BI  = GND
  C17  IOC17  BI  = PVCCIOMCP_CPU1
  C18  IOC18  BI  = PVCCIOMCP_CPU1
  C19  IOC19  BI  = PVCCIOMCP_CPU1
  C20  IOC20  BI  = FM_PVCCMCP_CPU1_EN
  D1  IOD1  BI  = P3V3
  D2  IOD2  BI  = GND
  D3  IOD3  BI  = GND
  D4  IOD4  BI  = GND
  D5  IOD5  BI  = GND
  D6  IOD6  BI  = GND
  D7  IOD7  BI  = GND
  D8  IOD8  BI  = GND
  D9  IOD9  BI  = GND
  D10  IOD10  BI  = GND
  D11  IOD11  BI  = GND
  D12  IOD12  BI  = GND
  D13  IOD13  BI  = GND
  D14  IOD14  BI  = GND
  D15  IOD15  BI  = GND
  D16  IOD16  BI  = GND
  D17  IOD17  BI  = PVCCIOMCP_CPU1
  D18  IOD18  BI  = PVCCIOMCP_CPU1
  D19  IOD19  BI  = PVCCIOMCP_CPU1
  D20  IOD20  BI  = PWRGD_PVCCMCP_CPU1
  E1  IOE1  BI  = FM_CPU1_VRM_322M_156M_OSC_EN
  E2  IOE2  BI  = GND
  E3  IOE3  BI  = GND
  E4  IOE4  BI  = GND
  E5  IOE5  BI  = GND
  E6  IOE6  BI  = GND
  E7  IOE7  BI  = GND
  E8  IOE8  BI  = VSENSE_PVCCIOMCP_CPU1_SKT_VSEN
  E9  IOE9  BI  = GND
  E10  IOE10  BI  = VR_PVCCIOMCP_CPU1_XADDR1
  E11  IOE11  BI  = GND
  E12  IOE12  BI  = GND
  E13  IOE13  BI  = GND
  E14  IOE14  BI  = GND
  E15  IOE15  BI  = PVCCIOMCP_CPU1
  E16  IOE16  BI  = PVCCIOMCP_CPU1
  E17  IOE17  BI  = PVCCIOMCP_CPU1
  E18  IOE18  BI  = PVCCIOMCP_CPU1
  E19  IOE19  BI  = PVCCIOMCP_CPU1
  E20  IOE20  BI  = SVID_CLK1_CPU1_R
  F1  IOF1  BI  = PVCCIO_CPU1
  F2  IOF2  BI  = GND
  F3  IOF3  BI  = GND
  F4  IOF4  BI  = GND
  F5  IOF5  BI  = GND
  F6  IOF6  BI  = GND
  F7  IOF7  BI  = GND
  F8  IOF8  BI  = VSENSE_PVCCIOMCP_CPU1_SKT_VRTN
  F9  IOF9  BI  = GND
  F10  IOF10  BI  = VR_PVCCMCP_CPU1_XADDR2
  F11  IOF11  BI  = GND
  F12  IOF12  BI  = GND
  F13  IOF13  BI  = GND
  F14  IOF14  BI  = GND
  F15  IOF15  BI  = PVCCIOMCP_CPU1
  F16  IOF16  BI  = PVCCIOMCP_CPU1
  F17  IOF17  BI  = PVCCIOMCP_CPU1
  F18  IOF18  BI  = PVCCIOMCP_CPU1
  F19  IOF19  BI  = PVCCIOMCP_CPU1
  F20  IOF20  BI  = SVID_DIO1_CPU1_R
